# S9S_MB_2U (Grand Teton) — schematic netlist excerpt (pin names and nets, part order shuffled) for the footprints in the layout excerpt that follows; sources: Cadence DE-HDL packaged netlist, KiCad conversion of 03242023_DA0F0TMBIJ0_F0T_Motherboard_J_brd_V01_OCP.brd

C1772  Q_CAP  1000PF 50V 5% EMPTY  pkg 0402  page 148 : A = RST_BMC_FROM_SWB_ISO_N ; B = GND
C2274  Q_CAP  0.1UF 25V 10% X7R  pkg 0402  page 170 : A = P3V3_AUX ; B = GND

(kicad_pcb
	(version 20260206)
	(generator "pcbnew")
	(generator_version "10.0")
	(general
		(thickness 1.6)
		(legacy_teardrops no)
	)
	(paper "A4")
	(title_block
		(title "03242023_DA0F0TMBIJ0_F0T_Motherboard_J_brd_V01_OCP.brd")
		(comment 1 "Grand Teton / footprints 2612-2613 of 6105")
	)
	(layers
		(0 "F.Cu" signal "TOP")
		(4 "In1.Cu" signal "GND")
		(6 "In2.Cu" signal "IN1")
		(8 "In3.Cu" signal "GND1")
		(10 "In4.Cu" signal "IN2")
		(12 "In5.Cu" signal "GND2")
		(14 "In6.Cu" signal "IN3")
		(16 "In7.Cu" signal "GND3")
		(18 "In8.Cu" signal "VCC")
		(20 "In9.Cu" signal "VCC1")
		(22 "In10.Cu" signal "GND4")
		(24 "In11.Cu" signal "IN4")
		(26 "In12.Cu" signal "GND5")
		(28 "In13.Cu" signal "IN5")
		(30 "In14.Cu" signal "GND6")
		(32 "In15.Cu" signal "IN6")
		(34 "In16.Cu" signal "GND7")
		(2 "B.Cu" signal "BOTTOM")
		(9 "F.Adhes" user "F.Adhesive")
		(11 "B.Adhes" user "B.Adhesive")
		(13 "F.Paste" user "Package Geometry/Pastemask Top")
		(15 "B.Paste" user "Package Geometry/Pastemask Bottom")
		(5 "F.SilkS" user "Ref Des/Silkscreen Top")
		(7 "B.SilkS" user "Ref Des/Silkscreen Bottom")
		(1 "F.Mask" user "Board Geometry/Soldermask Top")
		(3 "B.Mask" user "Board Geometry/Soldermask Bottom")
		(17 "Dwgs.User" user "User.Drawings")
		(19 "Cmts.User" user "User.Comments")
		(21 "Eco1.User" user "User.Eco1")
		(23 "Eco2.User" user "User.Eco2")
		(25 "Edge.Cuts" user "Board Geometry/Outline")
		(27 "Margin" user)
		(31 "F.CrtYd" user "Package Geometry/Place Bound Top")
		(29 "B.CrtYd" user "Package Geometry/Place Bound Bottom")
		(35 "F.Fab" user "Ref Des/Assembly Top")
		(33 "B.Fab" user "Ref Des/Assembly Bottom")
	)
	(footprint ""
		(layer "F.Cu")
		(at 424.204892 -380.329948 180)
		(property "Reference" "C1772"
			(at 0 0 180)
			(layer "F.SilkS")
			(hide yes)
			(effects
				(font
					(size 1.27 1.27)
				)
			)
		)
		(property "Value" ""
			(at 0 0 180)
			(layer "F.Fab")
			(effects
				(font
					(size 1.27 1.27)
				)
			)
		)
		(duplicate_pad_numbers_are_jumpers no)
		(fp_line
			(start 0.7874 0.4064)
			(end -0.7874 0.4064)
			(stroke
				(width 0.1524)
				(type default)
			)
			(layer "F.SilkS")
		)
		(fp_line
			(start 0.7874 -0.4064)
			(end 0.7874 0.4064)
			(stroke
				(width 0.1524)
				(type default)
			)
			(layer "F.SilkS")
		)
		(fp_line
			(start -0.7874 0.4064)
			(end -0.7874 -0.4064)
			(stroke
				(width 0.1524)
				(type default)
			)
			(layer "F.SilkS")
		)
		(fp_line
			(start -0.7874 -0.4064)
			(end 0.7874 -0.4064)
			(stroke
				(width 0.1524)
				(type default)
			)
			(layer "F.SilkS")
		)
		(fp_line
			(start 0.67945 0.3048)
			(end 0.120396 0.3048)
			(stroke
				(width 0.1)
				(type default)
			)
			(layer "F.Fab")
		)
		(fp_line
			(start 0.67945 -0.3048)
			(end 0.67945 0.3048)
			(stroke
				(width 0.1)
				(type default)
			)
			(layer "F.Fab")
		)
		(fp_line
			(start 0.12065 -0.2794)
			(end 0.12065 -0.3048)
			(stroke
				(width 0.1)
				(type default)
			)
			(layer "F.Fab")
		)
		(fp_line
			(start 0.12065 -0.3048)
			(end 0.67945 -0.3048)
			(stroke
				(width 0.1)
				(type default)
			)
			(layer "F.Fab")
		)
		(fp_line
			(start 0.120396 0.3048)
			(end 0.120396 0.2794)
			(stroke
				(width 0.1)
				(type default)
			)
			(layer "F.Fab")
		)
		(fp_line
			(start 0.120396 0.2794)
			(end -0.12065 0.2794)
			(stroke
				(width 0.1)
				(type default)
			)
			(layer "F.Fab")
		)
		(fp_line
			(start -0.12065 0.3048)
			(end -0.67945 0.3048)
			(stroke
				(width 0.1)
				(type default)
			)
			(layer "F.Fab")
		)
		(fp_line
			(start -0.12065 0.2794)
			(end -0.12065 0.3048)
			(stroke
				(width 0.1)
				(type default)
			)
			(layer "F.Fab")
		)
		(fp_line
			(start -0.12065 -0.2794)
			(end 0.12065 -0.2794)
			(stroke
				(width 0.1)
				(type default)
			)
			(layer "F.Fab")
		)
		(fp_line
			(start -0.12065 -0.305054)
			(end -0.12065 -0.2794)
			(stroke
				(width 0.1)
				(type default)
			)
			(layer "F.Fab")
		)
		(fp_line
			(start -0.67945 0.3048)
			(end -0.67945 -0.305054)
			(stroke
				(width 0.1)
				(type default)
			)
			(layer "F.Fab")
		)
		(fp_line
			(start -0.67945 -0.305054)
			(end -0.12065 -0.305054)
			(stroke
				(width 0.1)
				(type default)
			)
			(layer "F.Fab")
		)
		(pad "1" smd circle
			(at -0.40005 0 180)
			(size 0 0)
			(layers "F.Cu" "F.Mask" "F.Paste")
			(net "RST_BMC_FROM_SWB_ISO_N")
		)
		(pad "2" smd circle
			(at 0.40005 0 180)
			(size 0 0)
			(layers "F.Cu" "F.Mask" "F.Paste")
			(net "GND")
		)
	)
	(footprint ""
		(layer "F.Cu")
		(at 115.060222 -19.30019)
		(property "Reference" "C2274"
			(at 0 0 0)
			(layer "F.SilkS")
			(hide yes)
			(effects
				(font
					(size 1.27 1.27)
				)
			)
		)
		(property "Value" ""
			(at 0 0 0)
			(layer "F.Fab")
			(effects
				(font
					(size 1.27 1.27)
				)
			)
		)
		(duplicate_pad_numbers_are_jumpers no)
		(fp_line
			(start -0.7874 -0.4064)
			(end 0.7874 -0.4064)
			(stroke
				(width 0.1524)
				(type default)
			)
			(layer "F.SilkS")
		)
		(fp_line
			(start -0.7874 0.4064)
			(end -0.7874 -0.4064)
			(stroke
				(width 0.1524)
				(type default)
			)
			(layer "F.SilkS")
		)
		(fp_line
			(start 0.7874 -0.4064)
			(end 0.7874 0.4064)
			(stroke
				(width 0.1524)
				(type default)
			)
			(layer "F.SilkS")
		)
		(fp_line
			(start 0.7874 0.4064)
			(end -0.7874 0.4064)
			(stroke
				(width 0.1524)
				(type default)
			)
			(layer "F.SilkS")
		)
		(fp_line
			(start -0.67945 -0.305054)
			(end -0.12065 -0.305054)
			(stroke
				(width 0.1)
				(type default)
			)
			(layer "F.Fab")
		)
		(fp_line
			(start -0.67945 0.3048)
			(end -0.67945 -0.305054)
			(stroke
				(width 0.1)
				(type default)
			)
			(layer "F.Fab")
		)
		(fp_line
			(start -0.12065 -0.305054)
			(end -0.12065 -0.2794)
			(stroke
				(width 0.1)
				(type default)
			)
			(layer "F.Fab")
		)
		(fp_line
			(start -0.12065 -0.2794)
			(end 0.12065 -0.2794)
			(stroke
				(width 0.1)
				(type default)
			)
			(layer "F.Fab")
		)
		(fp_line
			(start -0.12065 0.2794)
			(end -0.12065 0.3048)
			(stroke
				(width 0.1)
				(type default)
			)
			(layer "F.Fab")
		)
		(fp_line
			(start -0.12065 0.3048)
			(end -0.67945 0.3048)
			(stroke
				(width 0.1)
				(type default)
			)
			(layer "F.Fab")
		)
		(fp_line
			(start 0.120396 0.2794)
			(end -0.12065 0.2794)
			(stroke
				(width 0.1)
				(type default)
			)
			(layer "F.Fab")
		)
		(fp_line
			(start 0.120396 0.3048)
			(end 0.120396 0.2794)
			(stroke
				(width 0.1)
				(type default)
			)
			(layer "F.Fab")
		)
		(fp_line
			(start 0.12065 -0.3048)
			(end 0.67945 -0.3048)
			(stroke
				(width 0.1)
				(type default)
			)
			(layer "F.Fab")
		)
		(fp_line
			(start 0.12065 -0.2794)
			(end 0.12065 -0.3048)
			(stroke
				(width 0.1)
				(type default)
			)
			(layer "F.Fab")
		)
		(fp_line
			(start 0.67945 -0.3048)
			(end 0.67945 0.3048)
			(stroke
				(width 0.1)
				(type default)
			)
			(layer "F.Fab")
		)
		(fp_line
			(start 0.67945 0.3048)
			(end 0.120396 0.3048)
			(stroke
				(width 0.1)
				(type default)
			)
			(layer "F.Fab")
		)
		(pad "1" smd circle
			(at -0.40005 0)
			(size 0 0)
			(layers "F.Cu" "F.Mask" "F.Paste")
			(net "P3V3_AUX")
		)
		(pad "2" smd circle
			(at 0.40005 0)
			(size 0 0)
			(layers "F.Cu" "F.Mask" "F.Paste")
			(net "GND")
		)
	)
)
